(kicad_pcb
	(version 20260206)
	(generator "pcbnew")
	(generator_version "10.0")
	(general
		(thickness 1.6)
		(legacy_teardrops no)
	)
	(paper "A4")
	(title_block
		(title "Wiwynn_Tioga_Pass_MB.brd")
		(comment 1 "Tioga Pass / footprints 4544-4551 of 4770")
	)
	(layers
		(0 "F.Cu" signal "TOP")
		(4 "In1.Cu" signal "L2GND")
		(6 "In2.Cu" signal "L3")
		(8 "In3.Cu" signal "L4GND")
		(10 "In4.Cu" signal "L5")
		(12 "In5.Cu" signal "L6GND")
		(14 "In6.Cu" signal "L7VCC")
		(16 "In7.Cu" signal "L8VCC")
		(18 "In8.Cu" signal "L9GND")
		(20 "In9.Cu" signal "L10")
		(22 "In10.Cu" signal "L11GND")
		(24 "In11.Cu" signal "L12")
		(26 "In12.Cu" signal "L13GND")
		(2 "B.Cu" signal "BOTTOM")
		(9 "F.Adhes" user "F.Adhesive")
		(11 "B.Adhes" user "B.Adhesive")
		(13 "F.Paste" user "Package Geometry/Pastemask Top")
		(15 "B.Paste" user "Package Geometry/Pastemask Bottom")
		(5 "F.SilkS" user "Ref Des/Silkscreen Top")
		(7 "B.SilkS" user "Ref Des/Silkscreen Bottom")
		(1 "F.Mask" user "Board Geometry/Soldermask Top")
		(3 "B.Mask" user "Board Geometry/Soldermask Bottom")
		(17 "Dwgs.User" user "User.Drawings")
		(19 "Cmts.User" user "User.Comments")
		(21 "Eco1.User" user "User.Eco1")
		(23 "Eco2.User" user "User.Eco2")
		(25 "Edge.Cuts" user "Board Geometry/Outline")
		(27 "Margin" user)
		(31 "F.CrtYd" user "Package Geometry/Place Bound Top")
		(29 "B.CrtYd" user "Package Geometry/Place Bound Bottom")
		(35 "F.Fab" user "Ref Des/Assembly Top")
		(33 "B.Fab" user "Ref Des/Assembly Bottom")
	)
	(footprint ""
		(layer "B.Cu")
		(at 498.602 -137.287 90)
		(property "Reference" "R1L44"
			(at 0 0 90)
			(layer "B.SilkS")
			(hide yes)
			(effects
				(font
					(size 1.27 1.27)
				)
				(justify mirror)
			)
		)
		(property "Value" ""
			(at 0 0 90)
			(layer "B.Fab")
			(effects
				(font
					(size 1.27 1.27)
				)
				(justify mirror)
			)
		)
		(duplicate_pad_numbers_are_jumpers no)
		(fp_poly
			(pts
				(xy 0.2794 -0.1016) (xy -0.2794 -0.1016) (xy -0.2794 0.9906) (xy 0.2794 0.9906)
			)
			(stroke
				(width 0)
				(type default)
			)
			(fill no)
			(layer "B.CrtYd")
		)
		(fp_line
			(start 0.2794 -0.1016)
			(end 0.2794 0.9906)
			(stroke
				(width 0.1)
				(type default)
			)
			(layer "B.Fab")
		)
		(fp_line
			(start -0.2794 -0.1016)
			(end 0.2794 -0.1016)
			(stroke
				(width 0.1)
				(type default)
			)
			(layer "B.Fab")
		)
		(fp_line
			(start 0.2794 0.9906)
			(end -0.2794 0.9906)
			(stroke
				(width 0.1)
				(type default)
			)
			(layer "B.Fab")
		)
		(fp_line
			(start -0.2794 0.9906)
			(end -0.2794 -0.1016)
			(stroke
				(width 0.1)
				(type default)
			)
			(layer "B.Fab")
		)
		(pad "1" smd rect
			(at 0 0 270)
			(size 0.508 0.508)
			(layers "B.Cu" "B.Mask" "B.Paste")
			(net "FM_UARTSW_MSB_R_N")
		)
		(pad "2" smd rect
			(at 0 0.889 270)
			(size 0.508 0.508)
			(layers "B.Cu" "B.Mask" "B.Paste")
			(net "P3V3_STBY")
		)
		(zone
			(layer "B.Cu")
			(hatch none 0.5)
			(connect_pads
				(clearance 0)
			)
			(min_thickness 0.25)
			(keepout
				(tracks allowed)
				(vias not_allowed)
				(pads allowed)
				(copperpour not_allowed)
				(footprints allowed)
			)
			(placement
				(enabled no)
				(sheetname "")
			)
			(fill
				(thermal_gap 0.5)
				(thermal_bridge_width 0.5)
				(island_removal_mode 0)
			)
			(polygon
				(pts
					(xy 498.856 -137.541) (xy 498.856 -137.033) (xy 499.237 -137.033) (xy 499.237 -137.541)
				)
			)
		)
		(zone
			(layer "B.Cu")
			(hatch none 0.5)
			(connect_pads
				(clearance 0)
			)
			(min_thickness 0.25)
			(keepout
				(tracks not_allowed)
				(vias allowed)
				(pads allowed)
				(copperpour not_allowed)
				(footprints allowed)
			)
			(placement
				(enabled no)
				(sheetname "")
			)
			(fill
				(thermal_gap 0.5)
				(thermal_bridge_width 0.5)
				(island_removal_mode 0)
			)
			(polygon
				(pts
					(xy 499.237 -137.541) (xy 499.237 -137.033) (xy 498.856 -137.033) (xy 498.856 -137.541)
				)
			)
		)
	)
	(footprint ""
		(layer "B.Cu")
		(at 155.064968 -154.782012 90)
		(property "Reference" "C7L2"
			(at 0 0 90)
			(layer "B.SilkS")
			(hide yes)
			(effects
				(font
					(size 1.27 1.27)
				)
				(justify mirror)
			)
		)
		(property "Value" ""
			(at 0 0 90)
			(layer "B.Fab")
			(effects
				(font
					(size 1.27 1.27)
				)
				(justify mirror)
			)
		)
		(duplicate_pad_numbers_are_jumpers no)
		(fp_rect
			(start 0.4953 1.6002)
			(end -0.4953 -0.2032)
			(stroke
				(width 0)
				(type default)
			)
			(fill no)
			(layer "B.CrtYd")
		)
		(fp_line
			(start 0.4953 -0.2032)
			(end -0.4953 -0.2032)
			(stroke
				(width 0.1)
				(type default)
			)
			(layer "B.Fab")
		)
		(fp_line
			(start -0.4953 -0.2032)
			(end -0.4953 1.6002)
			(stroke
				(width 0.1)
				(type default)
			)
			(layer "B.Fab")
		)
		(fp_line
			(start 0.4953 1.6002)
			(end 0.4953 -0.2032)
			(stroke
				(width 0.1)
				(type default)
			)
			(layer "B.Fab")
		)
		(fp_line
			(start -0.4953 1.6002)
			(end 0.4953 1.6002)
			(stroke
				(width 0.1)
				(type default)
			)
			(layer "B.Fab")
		)
		(pad "1" smd rect
			(at 0 0 270)
			(size 0.762 0.889)
			(layers "B.Cu" "B.Mask" "B.Paste")
			(net "PVPP_KLM")
		)
		(pad "2" smd rect
			(at 0 1.397 270)
			(size 0.762 0.889)
			(layers "B.Cu" "B.Mask" "B.Paste")
			(net "GND")
		)
		(zone
			(layer "B.Cu")
			(hatch none 0.5)
			(connect_pads
				(clearance 0)
			)
			(min_thickness 0.25)
			(keepout
				(tracks not_allowed)
				(vias allowed)
				(pads allowed)
				(copperpour not_allowed)
				(footprints allowed)
			)
			(placement
				(enabled no)
				(sheetname "")
			)
			(fill
				(thermal_gap 0.5)
				(thermal_bridge_width 0.5)
				(island_removal_mode 0)
			)
			(polygon
				(pts
					(xy 156.017468 -155.163012) (xy 155.509468 -155.163012) (xy 155.509468 -154.401012) (xy 156.017468 -154.401012)
				)
			)
		)
	)
	(footprint ""
		(layer "B.Cu")
		(at 338.76996 -77.694536 180)
		(property "Reference" "C3P11"
			(at 0 0 0)
			(layer "B.SilkS")
			(hide yes)
			(effects
				(font
					(size 1.27 1.27)
				)
				(justify mirror)
			)
		)
		(property "Value" ""
			(at 0 0 0)
			(layer "B.Fab")
			(effects
				(font
					(size 1.27 1.27)
				)
				(justify mirror)
			)
		)
		(duplicate_pad_numbers_are_jumpers no)
		(fp_poly
			(pts
				(xy -0.3048 -0.1016) (xy -0.3048 0.9906) (xy 0.3048 0.9906) (xy 0.3048 -0.1016)
			)
			(stroke
				(width 0)
				(type default)
			)
			(fill no)
			(layer "B.CrtYd")
		)
		(fp_line
			(start 0.3048 0.9906)
			(end -0.3048 0.9906)
			(stroke
				(width 0.1)
				(type default)
			)
			(layer "B.Fab")
		)
		(fp_line
			(start 0.3048 -0.1016)
			(end 0.3048 0.9906)
			(stroke
				(width 0.1)
				(type default)
			)
			(layer "B.Fab")
		)
		(fp_line
			(start -0.3048 0.9906)
			(end -0.3048 -0.1016)
			(stroke
				(width 0.1)
				(type default)
			)
			(layer "B.Fab")
		)
		(fp_line
			(start -0.3048 -0.1016)
			(end 0.3048 -0.1016)
			(stroke
				(width 0.1)
				(type default)
			)
			(layer "B.Fab")
		)
		(pad "1" smd rect
			(at 0 0)
			(size 0.508 0.508)
			(layers "B.Cu" "B.Mask" "B.Paste")
			(net "P3E_CPU0_PE1_SS_TXP<0>")
		)
		(pad "2" smd rect
			(at 0 0.889)
			(size 0.508 0.508)
			(layers "B.Cu" "B.Mask" "B.Paste")
			(net "P3E_CPU0_PE1_PCH_TXP<0>")
		)
		(zone
			(layer "B.Cu")
			(hatch none 0.5)
			(connect_pads
				(clearance 0)
			)
			(min_thickness 0.25)
			(keepout
				(tracks not_allowed)
				(vias allowed)
				(pads allowed)
				(copperpour not_allowed)
				(footprints allowed)
			)
			(placement
				(enabled no)
				(sheetname "")
			)
			(fill
				(thermal_gap 0.5)
				(thermal_bridge_width 0.5)
				(island_removal_mode 0)
			)
			(polygon
				(pts
					(xy 338.51596 -78.329536) (xy 339.02396 -78.329536) (xy 339.02396 -77.948536) (xy 338.51596 -77.948536)
				)
			)
		)
		(zone
			(layer "B.Cu")
			(hatch none 0.5)
			(connect_pads
				(clearance 0)
			)
			(min_thickness 0.25)
			(keepout
				(tracks allowed)
				(vias not_allowed)
				(pads allowed)
				(copperpour not_allowed)
				(footprints allowed)
			)
			(placement
				(enabled no)
				(sheetname "")
			)
			(fill
				(thermal_gap 0.5)
				(thermal_bridge_width 0.5)
				(island_removal_mode 0)
			)
			(polygon
				(pts
					(xy 338.51596 -77.948536) (xy 339.02396 -77.948536) (xy 339.02396 -78.329536) (xy 338.51596 -78.329536)
				)
			)
		)
	)
	(footprint ""
		(layer "B.Cu")
		(at 264.1346 -124.6886 -90)
		(property "Reference" "SH4L1"
			(at 0 0 90)
			(layer "B.SilkS")
			(hide yes)
			(effects
				(font
					(size 1.27 1.27)
				)
				(justify mirror)
			)
		)
		(property "Value" ""
			(at 0 0 90)
			(layer "B.Fab")
			(effects
				(font
					(size 1.27 1.27)
				)
				(justify mirror)
			)
		)
		(duplicate_pad_numbers_are_jumpers no)
		(fp_poly
			(pts
				(xy 0.1651 -0.0508) (xy 0.1651 0.5842) (xy -0.1651 0.5842) (xy -0.1651 -0.0508)
			)
			(stroke
				(width 0)
				(type default)
			)
			(fill no)
			(layer "B.CrtYd")
		)
		(fp_line
			(start -0.1651 0.5842)
			(end 0.1651 0.5842)
			(stroke
				(width 0.1)
				(type default)
			)
			(layer "B.Fab")
		)
		(fp_line
			(start 0.1651 0.5842)
			(end 0.1651 -0.0508)
			(stroke
				(width 0.1)
				(type default)
			)
			(layer "B.Fab")
		)
		(fp_line
			(start -0.1651 -0.0508)
			(end -0.1651 0.5842)
			(stroke
				(width 0.1)
				(type default)
			)
			(layer "B.Fab")
		)
		(fp_line
			(start 0.1651 -0.0508)
			(end -0.1651 -0.0508)
			(stroke
				(width 0.1)
				(type default)
			)
			(layer "B.Fab")
		)
		(pad "1" smd custom
			(at 0 0 270)
			(size 0.0762 0.0762)
			(layers "B.Cu" "B.Mask" "B.Paste")
			(net "VSENSE_PVDDQ_DEF_N")
			(options
				(clearance outline)
				(anchor circle)
			)
			(primitives
				(gr_poly
					(pts
						(arc
							(start -0.1524 0.10795)
							(mid -0.098518 0.130268)
							(end -0.0762 0.18415)
						)
						(xy -0.0762 0.22225) (xy 0.0762 0.22225)
						(arc
							(start 0.0762 0.18415)
							(mid 0.098518 0.130268)
							(end 0.1524 0.10795)
						)
						(xy 0.1524 -0.22225) (xy -0.1524 -0.22225)
					)
					(width 0)
					(fill yes)
				)
			)
		)
		(pad "2" smd custom
			(at 0 0.5334 90)
			(size 0.0762 0.0762)
			(layers "B.Cu" "B.Mask" "B.Paste")
			(net "GND")
			(options
				(clearance outline)
				(anchor circle)
			)
			(primitives
				(gr_poly
					(pts
						(arc
							(start -0.1524 0.10795)
							(mid -0.098518 0.130268)
							(end -0.0762 0.18415)
						)
						(xy -0.0762 0.22225) (xy 0.0762 0.22225)
						(arc
							(start 0.0762 0.18415)
							(mid 0.098518 0.130268)
							(end 0.1524 0.10795)
						)
						(xy 0.1524 -0.22225) (xy -0.1524 -0.22225)
					)
					(width 0)
					(fill yes)
				)
			)
		)
	)
	(footprint ""
		(layer "B.Cu")
		(at 455.676 -116.49202)
		(property "Reference" "C1M13"
			(at 0 0 0)
			(layer "B.SilkS")
			(hide yes)
			(effects
				(font
					(size 1.27 1.27)
				)
				(justify mirror)
			)
		)
		(property "Value" ""
			(at 0 0 0)
			(layer "B.Fab")
			(effects
				(font
					(size 1.27 1.27)
				)
				(justify mirror)
			)
		)
		(duplicate_pad_numbers_are_jumpers no)
		(fp_rect
			(start -0.3048 0.9906)
			(end 0.3048 -0.1016)
			(stroke
				(width 0)
				(type default)
			)
			(fill no)
			(layer "B.CrtYd")
		)
		(fp_line
			(start -0.3048 -0.1016)
			(end 0.3048 -0.1016)
			(stroke
				(width 0.1)
				(type default)
			)
			(layer "B.Fab")
		)
		(fp_line
			(start -0.3048 0.9906)
			(end -0.3048 -0.1016)
			(stroke
				(width 0.1)
				(type default)
			)
			(layer "B.Fab")
		)
		(fp_line
			(start 0.3048 -0.1016)
			(end 0.3048 0.9906)
			(stroke
				(width 0.1)
				(type default)
			)
			(layer "B.Fab")
		)
		(fp_line
			(start 0.3048 0.9906)
			(end -0.3048 0.9906)
			(stroke
				(width 0.1)
				(type default)
			)
			(layer "B.Fab")
		)
		(pad "1" smd rect
			(at 0 0 180)
			(size 0.508 0.508)
			(layers "B.Cu" "B.Mask" "B.Paste")
			(net "P3E_CPU0_PE3_OCP_TXN<12>")
		)
		(pad "2" smd rect
			(at 0 0.889 180)
			(size 0.508 0.508)
			(layers "B.Cu" "B.Mask" "B.Paste")
			(net "P3E_OCP_CPU0_PE3_C_TXN<12>")
		)
		(zone
			(layer "B.Cu")
			(hatch none 0.5)
			(connect_pads
				(clearance 0)
			)
			(min_thickness 0.25)
			(keepout
				(tracks allowed)
				(vias not_allowed)
				(pads allowed)
				(copperpour not_allowed)
				(footprints allowed)
			)
			(placement
				(enabled no)
				(sheetname "")
			)
			(fill
				(thermal_gap 0.5)
				(thermal_bridge_width 0.5)
				(island_removal_mode 0)
			)
			(polygon
				(pts
					(xy 455.422 -115.85702) (xy 455.93 -115.85702) (xy 455.93 -116.23802) (xy 455.422 -116.23802)
				)
			)
		)
		(zone
			(layer "B.Cu")
			(hatch none 0.5)
			(connect_pads
				(clearance 0)
			)
			(min_thickness 0.25)
			(keepout
				(tracks not_allowed)
				(vias allowed)
				(pads allowed)
				(copperpour not_allowed)
				(footprints allowed)
			)
			(placement
				(enabled no)
				(sheetname "")
			)
			(fill
				(thermal_gap 0.5)
				(thermal_bridge_width 0.5)
				(island_removal_mode 0)
			)
			(polygon
				(pts
					(xy 455.422 -115.85702) (xy 455.93 -115.85702) (xy 455.93 -116.23802) (xy 455.422 -116.23802)
				)
			)
		)
	)
	(footprint ""
		(layer "B.Cu")
		(at 427.9519 -18.034 90)
		(property "Reference" "R1U22"
			(at 0 0 90)
			(layer "B.SilkS")
			(hide yes)
			(effects
				(font
					(size 1.27 1.27)
				)
				(justify mirror)
			)
		)
		(property "Value" ""
			(at 0 0 90)
			(layer "B.Fab")
			(effects
				(font
					(size 1.27 1.27)
				)
				(justify mirror)
			)
		)
		(duplicate_pad_numbers_are_jumpers no)
		(fp_poly
			(pts
				(xy 0.2794 -0.1016) (xy -0.2794 -0.1016) (xy -0.2794 0.9906) (xy 0.2794 0.9906)
			)
			(stroke
				(width 0)
				(type default)
			)
			(fill no)
			(layer "B.CrtYd")
		)
		(fp_line
			(start 0.2794 -0.1016)
			(end 0.2794 0.9906)
			(stroke
				(width 0.1)
				(type default)
			)
			(layer "B.Fab")
		)
		(fp_line
			(start -0.2794 -0.1016)
			(end 0.2794 -0.1016)
			(stroke
				(width 0.1)
				(type default)
			)
			(layer "B.Fab")
		)
		(fp_line
			(start 0.2794 0.9906)
			(end -0.2794 0.9906)
			(stroke
				(width 0.1)
				(type default)
			)
			(layer "B.Fab")
		)
		(fp_line
			(start -0.2794 0.9906)
			(end -0.2794 -0.1016)
			(stroke
				(width 0.1)
				(type default)
			)
			(layer "B.Fab")
		)
		(pad "1" smd rect
			(at 0 0 270)
			(size 0.508 0.508)
			(layers "B.Cu" "B.Mask" "B.Paste")
			(net "P3V3_STBY")
		)
		(pad "2" smd rect
			(at 0 0.889 270)
			(size 0.508 0.508)
			(layers "B.Cu" "B.Mask" "B.Paste")
			(net "FM_BOARD_SKU_ID1")
		)
		(zone
			(layer "B.Cu")
			(hatch none 0.5)
			(connect_pads
				(clearance 0)
			)
			(min_thickness 0.25)
			(keepout
				(tracks allowed)
				(vias not_allowed)
				(pads allowed)
				(copperpour not_allowed)
				(footprints allowed)
			)
			(placement
				(enabled no)
				(sheetname "")
			)
			(fill
				(thermal_gap 0.5)
				(thermal_bridge_width 0.5)
				(island_removal_mode 0)
			)
			(polygon
				(pts
					(xy 428.2059 -18.288) (xy 428.2059 -17.78) (xy 428.5869 -17.78) (xy 428.5869 -18.288)
				)
			)
		)
		(zone
			(layer "B.Cu")
			(hatch none 0.5)
			(connect_pads
				(clearance 0)
			)
			(min_thickness 0.25)
			(keepout
				(tracks not_allowed)
				(vias allowed)
				(pads allowed)
				(copperpour not_allowed)
				(footprints allowed)
			)
			(placement
				(enabled no)
				(sheetname "")
			)
			(fill
				(thermal_gap 0.5)
				(thermal_bridge_width 0.5)
				(island_removal_mode 0)
			)
			(polygon
				(pts
					(xy 428.5869 -18.288) (xy 428.5869 -17.78) (xy 428.2059 -17.78) (xy 428.2059 -18.288)
				)
			)
		)
	)
	(footprint ""
		(layer "B.Cu")
		(at 265.864086 -73.51014)
		(property "Reference" "C5P33"
			(at 0 0 0)
			(layer "B.SilkS")
			(hide yes)
			(effects
				(font
					(size 1.27 1.27)
				)
				(justify mirror)
			)
		)
		(property "Value" ""
			(at 0 0 0)
			(layer "B.Fab")
			(effects
				(font
					(size 1.27 1.27)
				)
				(justify mirror)
			)
		)
		(duplicate_pad_numbers_are_jumpers no)
		(fp_poly
			(pts
				(xy 0.7239 -0.2159) (xy -0.7239 -0.2159) (xy -0.7239 1.9939) (xy 0.7239 1.9939)
			)
			(stroke
				(width 0)
				(type default)
			)
			(fill no)
			(layer "B.CrtYd")
		)
		(fp_line
			(start -0.7239 -0.2159)
			(end 0.7239 -0.2159)
			(stroke
				(width 0.1)
				(type default)
			)
			(layer "B.Fab")
		)
		(fp_line
			(start -0.7239 1.9939)
			(end -0.7239 -0.2159)
			(stroke
				(width 0.1)
				(type default)
			)
			(layer "B.Fab")
		)
		(fp_line
			(start 0.7239 -0.2159)
			(end 0.7239 1.9939)
			(stroke
				(width 0.1)
				(type default)
			)
			(layer "B.Fab")
		)
		(fp_line
			(start 0.7239 1.9939)
			(end -0.7239 1.9939)
			(stroke
				(width 0.1)
				(type default)
			)
			(layer "B.Fab")
		)
		(pad "1" smd rect
			(at 0 0 180)
			(size 1.27 1.016)
			(layers "B.Cu" "B.Mask" "B.Paste")
			(net "PVCCIN_CPU0")
		)
		(pad "2" smd rect
			(at 0 1.778 180)
			(size 1.27 1.016)
			(layers "B.Cu" "B.Mask" "B.Paste")
			(net "GND")
		)
		(zone
			(layer "B.Cu")
			(hatch none 0.5)
			(connect_pads
				(clearance 0)
			)
			(min_thickness 0.25)
			(keepout
				(tracks not_allowed)
				(vias allowed)
				(pads allowed)
				(copperpour not_allowed)
				(footprints allowed)
			)
			(placement
				(enabled no)
				(sheetname "")
			)
			(fill
				(thermal_gap 0.5)
				(thermal_bridge_width 0.5)
				(island_removal_mode 0)
			)
			(polygon
				(pts
					(xy 266.499086 -73.00214) (xy 265.229086 -73.00214) (xy 265.229086 -72.24014) (xy 266.499086 -72.24014)
				)
			)
		)
	)
	(footprint ""
		(layer "B.Cu")
		(at 3.8227 -9.564116 90)
		(property "Reference" "C9U4"
			(at 0 0 90)
			(layer "B.SilkS")
			(hide yes)
			(effects
				(font
					(size 1.27 1.27)
				)
				(justify mirror)
			)
		)
		(property "Value" ""
			(at 0 0 90)
			(layer "B.Fab")
			(effects
				(font
					(size 1.27 1.27)
				)
				(justify mirror)
			)
		)
		(duplicate_pad_numbers_are_jumpers no)
		(fp_rect
			(start -0.7239 -0.2159)
			(end 0.7239 1.9939)
			(stroke
				(width 0)
				(type default)
			)
			(fill no)
			(layer "B.CrtYd")
		)
		(fp_line
			(start 0.7239 -0.2159)
			(end 0.7239 1.9939)
			(stroke
				(width 0.1)
				(type default)
			)
			(layer "B.Fab")
		)
		(fp_line
			(start -0.7239 -0.2159)
			(end 0.7239 -0.2159)
			(stroke
				(width 0.1)
				(type default)
			)
			(layer "B.Fab")
		)
		(fp_line
			(start 0.7239 1.9939)
			(end -0.7239 1.9939)
			(stroke
				(width 0.1)
				(type default)
			)
			(layer "B.Fab")
		)
		(fp_line
			(start -0.7239 1.9939)
			(end -0.7239 -0.2159)
			(stroke
				(width 0.1)
				(type default)
			)
			(layer "B.Fab")
		)
		(pad "1" smd rect
			(at 0 0 270)
			(size 1.27 1.016)
			(layers "B.Cu" "B.Mask" "B.Paste")
			(net "VR_FET_SW_P12V_STBY_PVDDQ_GHJ")
		)
		(pad "2" smd rect
			(at 0 1.778 270)
			(size 1.27 1.016)
			(layers "B.Cu" "B.Mask" "B.Paste")
			(net "GND")
		)
		(zone
			(layer "B.Cu")
			(hatch none 0.5)
			(connect_pads
				(clearance 0)
			)
			(min_thickness 0.25)
			(keepout
				(tracks not_allowed)
				(vias allowed)
				(pads allowed)
				(copperpour not_allowed)
				(footprints allowed)
			)
			(placement
				(enabled no)
				(sheetname "")
			)
			(fill
				(thermal_gap 0.5)
				(thermal_bridge_width 0.5)
				(island_removal_mode 0)
			)
			(polygon
				(pts
					(xy 4.3307 -8.929116) (xy 5.0927 -8.929116) (xy 5.0927 -10.199116) (xy 4.3307 -10.199116)
				)
			)
		)
	)
)
